(kicad_pcb
	(version 20260206)
	(generator "pcbnew")
	(generator_version "10.0")
	(general
		(thickness 1.59074)
		(legacy_teardrops no)
	)
	(paper "A4")
	(title_block
		(title "osc-sa45 — FAB_SA45_DaughterCard.PcbDoc")
		(comment 1 "Time Appliance Project (Time Card) / footprints 23-30 of 44")
	)
	(layers
		(0 "F.Cu" signal "L01-Top Layer")
		(4 "In1.Cu" signal "L02-Inner Layer")
		(6 "In2.Cu" signal "L03-Inner Layer")
		(2 "B.Cu" signal "L04-Bottom Layer")
		(9 "F.Adhes" user "F.Adhesive")
		(11 "B.Adhes" user "B.Adhesive")
		(13 "F.Paste" user "Top Paste")
		(15 "B.Paste" user "Bottom Paste")
		(5 "F.SilkS" user "Top Overlay")
		(7 "B.SilkS" user "Bottom Overlay")
		(1 "F.Mask" user "Top Solder")
		(3 "B.Mask" user "Bottom Solder")
		(17 "Dwgs.User" user "User.Drawings")
		(19 "Cmts.User" user "User.Comments")
		(21 "Eco1.User" user "User.Eco1")
		(23 "Eco2.User" user "User.Eco2")
		(25 "Edge.Cuts" user)
		(27 "Margin" user)
		(31 "F.CrtYd" user "Top Courtyard")
		(29 "B.CrtYd" user "Bottom Courtyard")
		(35 "F.Fab" user "Top Component Outline")
		(33 "B.Fab" user "Bottom Component Outline 2")
	)
	(footprint "Vault:RESC1005X040N"
		(layer "B.Cu")
		(at 142.546105 106.178605)
		(property "Reference" "R2"
			(at -2.32 -0.12517 0)
			(unlocked yes)
			(layer "B.SilkS")
			(effects
				(font
					(face "Arial")
					(size 0.63 0.63)
					(thickness 0.254)
				)
				(justify mirror)
			)
		)
		(property "Value" "Yageo_RC0402FR-0791KL"
			(at -9.98758 12.23942 0)
			(unlocked yes)
			(layer "B.SilkS")
			(hide yes)
			(effects
				(font
					(face "Arial")
					(size 0.63 0.63)
					(thickness 0.254)
				)
				(justify mirror)
			)
		)
		(sheetname "SCH_SA45_DaughterCard")
		(sheetfile "SCH_SA45_DaughterCard.kicad_sch")
		(duplicate_pad_numbers_are_jumpers no)
		(fp_line
			(start -0.95 -0.5)
			(end 0.95 -0.5)
			(stroke
				(width 0.1)
				(type solid)
			)
			(layer "B.CrtYd")
		)
		(fp_line
			(start -0.95 0.5)
			(end -0.95 -0.5)
			(stroke
				(width 0.1)
				(type solid)
			)
			(layer "B.CrtYd")
		)
		(fp_line
			(start -0.95 0.5)
			(end 0.95 0.5)
			(stroke
				(width 0.1)
				(type solid)
			)
			(layer "B.CrtYd")
		)
		(fp_line
			(start 0.95 0.5)
			(end 0.95 -0.5)
			(stroke
				(width 0.1)
				(type solid)
			)
			(layer "B.CrtYd")
		)
		(fp_line
			(start -0.5 -0.25)
			(end 0.5 -0.25)
			(stroke
				(width 0.05)
				(type solid)
			)
			(layer "B.Fab")
		)
		(fp_line
			(start -0.5 0.25)
			(end -0.5 -0.25)
			(stroke
				(width 0.05)
				(type solid)
			)
			(layer "B.Fab")
		)
		(fp_line
			(start -0.5 0.25)
			(end 0.5 0.25)
			(stroke
				(width 0.05)
				(type solid)
			)
			(layer "B.Fab")
		)
		(fp_line
			(start 0.5 0.25)
			(end 0.5 -0.25)
			(stroke
				(width 0.05)
				(type solid)
			)
			(layer "B.Fab")
		)
		(fp_text_box "${REFERENCE}"
			(start -1.09004 -0.20727)
			(end 1.09004 0.20726)
			(margins 0 0 0 0)
			(layer "B.Fab")
			(effects
				(font
					(face "Arial")
					(size 0.315 0.315)
					(thickness 0.254)
				)
				(justify top mirror)
			)
			(border no)
			(stroke
				(width 0.1)
				(type default)
			)
			(knockout no)
		)
		(pad "1" smd rect
			(at -0.48 0)
			(size 0.57 0.62)
			(layers "B.Cu" "B.Mask" "B.Paste")
			(net "+3.3V")
			(solder_mask_margin 0.05)
			(solder_paste_margin 0)
		)
		(pad "2" smd rect
			(at 0.48 0)
			(size 0.57 0.62)
			(layers "B.Cu" "B.Mask" "B.Paste")
			(net "NetC4_2")
			(solder_mask_margin 0.05)
			(solder_paste_margin 0)
		)
	)
	(footprint "Vault:TH001V_109DIA_000mt_8600-0"
		(layer "B.Cu")
		(at 130.239105 81.993605 180)
		(property "Reference" "P6"
			(at 0.000005 1.68071 0)
			(unlocked yes)
			(layer "B.SilkS")
			(effects
				(font
					(face "Arial")
					(size 0.63 0.63)
					(thickness 0.254)
				)
				(justify mirror)
			)
		)
		(property "Value" "Mill-Max_8600-0-05-80-00-00-03-0"
			(at 22.534825 -2.89778 0)
			(unlocked yes)
			(layer "B.SilkS")
			(hide yes)
			(effects
				(font
					(face "Arial")
					(size 0.63 0.63)
					(thickness 0.254)
				)
				(justify mirror)
			)
		)
		(sheetname "SCH_SA45_DaughterCard")
		(sheetfile "SCH_SA45_DaughterCard.kicad_sch")
		(duplicate_pad_numbers_are_jumpers no)
		(fp_line
			(start 1.4 1.4)
			(end -1.4 1.4)
			(stroke
				(width 0.1)
				(type solid)
			)
			(layer "B.CrtYd")
		)
		(fp_line
			(start 1.4 -1.4)
			(end 1.4 1.4)
			(stroke
				(width 0.1)
				(type solid)
			)
			(layer "B.CrtYd")
		)
		(fp_line
			(start 1.4 -1.4)
			(end -1.4 -1.4)
			(stroke
				(width 0.1)
				(type solid)
			)
			(layer "B.CrtYd")
		)
		(fp_line
			(start -1.4 -1.4)
			(end -1.4 1.4)
			(stroke
				(width 0.1)
				(type solid)
			)
			(layer "B.CrtYd")
		)
		(fp_circle
			(center 0 0)
			(end 0 0.545)
			(stroke
				(width 0.1)
				(type solid)
			)
			(fill no)
			(layer "B.Fab")
		)
		(fp_text user "${REFERENCE}"
			(at 0 0.166251 360)
			(unlocked yes)
			(layer "B.Fab")
			(effects
				(font
					(face "Arial")
					(size 0.8001 0.8001)
					(thickness 0.254)
				)
				(justify mirror)
			)
		)
		(pad "1" thru_hole circle
			(at 0 -0.02 180)
			(size 2.09 2.09)
			(drill 1.09)
			(layers "*.Cu" "*.Mask")
			(remove_unused_layers no)
			(net "LOCK")
			(solder_mask_margin 0.05)
			(solder_paste_margin -2147.48364)
			(thermal_bridge_angle 90)
		)
	)
	(footprint "Vault:RESC0603X026N"
		(layer "B.Cu")
		(at 144.026105 104.788605 90)
		(property "Reference" "R6"
			(at 3.41026 -0.210005 0)
			(unlocked yes)
			(layer "B.SilkS")
			(effects
				(font
					(face "Arial")
					(size 0.63 0.63)
					(thickness 0.254)
				)
				(justify mirror)
			)
		)
		(property "Value" "Yageo_RC0201JR-070RL"
			(at -12.38782 -12.63902 0)
			(unlocked yes)
			(layer "B.SilkS")
			(hide yes)
			(effects
				(font
					(face "Arial")
					(size 0.63 0.63)
					(thickness 0.254)
				)
				(justify mirror)
			)
		)
		(sheetname "SCH_SA45_DaughterCard")
		(sheetfile "SCH_SA45_DaughterCard.kicad_sch")
		(duplicate_pad_numbers_are_jumpers no)
		(fp_line
			(start 0.75 -0.4)
			(end 0.75 0.4)
			(stroke
				(width 0.1)
				(type solid)
			)
			(layer "B.CrtYd")
		)
		(fp_line
			(start -0.75 -0.4)
			(end 0.75 -0.4)
			(stroke
				(width 0.1)
				(type solid)
			)
			(layer "B.CrtYd")
		)
		(fp_line
			(start -0.75 -0.4)
			(end -0.75 0.4)
			(stroke
				(width 0.1)
				(type solid)
			)
			(layer "B.CrtYd")
		)
		(fp_line
			(start -0.75 0.4)
			(end 0.75 0.4)
			(stroke
				(width 0.1)
				(type solid)
			)
			(layer "B.CrtYd")
		)
		(fp_line
			(start 0.3 -0.15)
			(end 0.3 0.15)
			(stroke
				(width 0.05)
				(type solid)
			)
			(layer "B.Fab")
		)
		(fp_line
			(start -0.3 -0.15)
			(end 0.3 -0.15)
			(stroke
				(width 0.05)
				(type solid)
			)
			(layer "B.Fab")
		)
		(fp_line
			(start -0.3 -0.15)
			(end -0.3 0.15)
			(stroke
				(width 0.05)
				(type solid)
			)
			(layer "B.Fab")
		)
		(fp_line
			(start -0.3 0.15)
			(end 0.3 0.15)
			(stroke
				(width 0.05)
				(type solid)
			)
			(layer "B.Fab")
		)
		(fp_text_box "${REFERENCE}"
			(start 0.20727 -1.09004)
			(end -0.20726 1.09004)
			(margins 0 0 0 0)
			(angle -90)
			(layer "B.Fab")
			(effects
				(font
					(face "Arial")
					(size 0.315 0.315)
					(thickness 0.254)
				)
				(justify top mirror)
			)
			(border no)
			(stroke
				(width 0.1)
				(type default)
			)
			(knockout no)
		)
		(pad "1" smd rect
			(at -0.34 0 90)
			(size 0.44 0.42)
			(layers "B.Cu" "B.Mask" "B.Paste")
			(net "NetR5_1")
			(solder_mask_margin 0.05)
			(solder_paste_margin 0)
		)
		(pad "2" smd rect
			(at 0.34 0 90)
			(size 0.44 0.42)
			(layers "B.Cu" "B.Mask" "B.Paste")
			(net "GND")
			(solder_mask_margin 0.05)
			(solder_paste_margin 0)
		)
	)
	(footprint "Vault:CAPC2013X140N"
		(layer "B.Cu")
		(at 151.476105 117.553605 180)
		(property "Reference" "C11"
			(at -2.95163 0.12656 0)
			(unlocked yes)
			(layer "B.SilkS")
			(effects
				(font
					(face "Arial")
					(size 0.63 0.63)
					(thickness 0.254)
				)
				(justify mirror)
			)
		)
		(property "Value" "Murata_GRM21BR61A226ME51L"
			(at 19.40959 6.33785 0)
			(unlocked yes)
			(layer "B.SilkS")
			(hide yes)
			(effects
				(font
					(face "Arial")
					(size 0.63 0.63)
					(thickness 0.254)
				)
				(justify mirror)
			)
		)
		(sheetname "SCH_SA45_DaughterCard")
		(sheetfile "SCH_SA45_DaughterCard.kicad_sch")
		(duplicate_pad_numbers_are_jumpers no)
		(fp_line
			(start 1.8 1.1)
			(end -1.8 1.1)
			(stroke
				(width 0.1)
				(type solid)
			)
			(layer "B.CrtYd")
		)
		(fp_line
			(start 1.8 -1.1)
			(end 1.8 1.1)
			(stroke
				(width 0.1)
				(type solid)
			)
			(layer "B.CrtYd")
		)
		(fp_line
			(start 1.8 -1.1)
			(end -1.8 -1.1)
			(stroke
				(width 0.1)
				(type solid)
			)
			(layer "B.CrtYd")
		)
		(fp_line
			(start -1.8 -1.1)
			(end -1.8 1.1)
			(stroke
				(width 0.1)
				(type solid)
			)
			(layer "B.CrtYd")
		)
		(fp_line
			(start 1 0.65)
			(end -1 0.65)
			(stroke
				(width 0.05)
				(type solid)
			)
			(layer "B.Fab")
		)
		(fp_line
			(start 1 -0.65)
			(end 1 0.65)
			(stroke
				(width 0.05)
				(type solid)
			)
			(layer "B.Fab")
		)
		(fp_line
			(start 1 -0.65)
			(end -1 -0.65)
			(stroke
				(width 0.05)
				(type solid)
			)
			(layer "B.Fab")
		)
		(fp_line
			(start -1 -0.65)
			(end -1 0.65)
			(stroke
				(width 0.05)
				(type solid)
			)
			(layer "B.Fab")
		)
		(fp_text_box "${REFERENCE}"
			(start 1.09004 0.20729)
			(end -1.09004 -0.20729)
			(margins 0 0 0 0)
			(angle -180)
			(layer "B.Fab")
			(effects
				(font
					(face "Arial")
					(size 0.315 0.315)
					(thickness 0.254)
				)
				(justify top mirror)
			)
			(border no)
			(stroke
				(width 0.1)
				(type default)
			)
			(knockout no)
		)
		(pad "1" smd rect
			(at -0.9 0 180)
			(size 1.3 1.65)
			(layers "B.Cu" "B.Mask" "B.Paste")
			(net "+3.3V")
			(solder_mask_margin 0.05)
			(solder_paste_margin 0)
		)
		(pad "2" smd rect
			(at 0.9 0 180)
			(size 1.3 1.65)
			(layers "B.Cu" "B.Mask" "B.Paste")
			(net "GND")
			(solder_mask_margin 0.05)
			(solder_paste_margin 0)
		)
	)
	(footprint "Vault:RESC3216X070N"
		(layer "B.Cu")
		(at 161.901105 117.703605)
		(property "Reference" "R3"
			(at 0.000005 -2.12071 0)
			(unlocked yes)
			(layer "B.SilkS")
			(effects
				(font
					(face "Arial")
					(size 0.63 0.63)
					(thickness 0.254)
				)
				(justify mirror)
			)
		)
		(property "Value" "Yageo_RC1206JR-070RL"
			(at 4.77019 0.63171 0)
			(unlocked yes)
			(layer "B.SilkS")
			(hide yes)
			(effects
				(font
					(face "Arial")
					(size 0.63 0.63)
					(thickness 0.254)
				)
				(justify mirror)
			)
		)
		(sheetname "SCH_SA45_DaughterCard")
		(sheetfile "SCH_SA45_DaughterCard.kicad_sch")
		(duplicate_pad_numbers_are_jumpers no)
		(fp_line
			(start -0.7 -0.9)
			(end 0.7 -0.9)
			(stroke
				(width 0.1)
				(type solid)
			)
			(layer "B.SilkS")
		)
		(fp_line
			(start -0.7 0.9)
			(end 0.7 0.9)
			(stroke
				(width 0.1)
				(type solid)
			)
			(layer "B.SilkS")
		)
		(fp_line
			(start -2.3 -1.15)
			(end 2.3 -1.15)
			(stroke
				(width 0.1)
				(type solid)
			)
			(layer "B.CrtYd")
		)
		(fp_line
			(start -2.3 1.15)
			(end -2.3 -1.15)
			(stroke
				(width 0.1)
				(type solid)
			)
			(layer "B.CrtYd")
		)
		(fp_line
			(start -2.3 1.15)
			(end 2.3 1.15)
			(stroke
				(width 0.1)
				(type solid)
			)
			(layer "B.CrtYd")
		)
		(fp_line
			(start 2.3 1.15)
			(end 2.3 -1.15)
			(stroke
				(width 0.1)
				(type solid)
			)
			(layer "B.CrtYd")
		)
		(fp_line
			(start -1.6 -0.8)
			(end 1.6 -0.8)
			(stroke
				(width 0.05)
				(type solid)
			)
			(layer "B.Fab")
		)
		(fp_line
			(start -1.6 0.8)
			(end -1.6 -0.8)
			(stroke
				(width 0.05)
				(type solid)
			)
			(layer "B.Fab")
		)
		(fp_line
			(start -1.6 0.8)
			(end 1.6 0.8)
			(stroke
				(width 0.05)
				(type solid)
			)
			(layer "B.Fab")
		)
		(fp_line
			(start 1.6 0.8)
			(end 1.6 -0.8)
			(stroke
				(width 0.05)
				(type solid)
			)
			(layer "B.Fab")
		)
		(fp_text_box "${REFERENCE}"
			(start 1.14717 0.20754)
			(end -1.14713 -0.20759)
			(margins 0 0 0 0)
			(angle 180)
			(layer "B.Fab")
			(effects
				(font
					(face "Arial")
					(size 0.315 0.315)
					(thickness 0.254)
				)
				(justify top mirror)
			)
			(border no)
			(stroke
				(width 0.1)
				(type default)
			)
			(knockout no)
		)
		(pad "1" smd rect
			(at -1.5 0)
			(size 1.05 1.75)
			(layers "B.Cu" "B.Mask" "B.Paste")
			(net "+3.3V")
			(solder_mask_margin 0.05)
			(solder_paste_margin 0)
		)
		(pad "2" smd rect
			(at 1.5 0)
			(size 1.05 1.75)
			(layers "B.Cu" "B.Mask" "B.Paste")
			(net "+3.3V_OSC")
			(solder_mask_margin 0.05)
			(solder_paste_margin 0)
		)
	)
	(footprint "Vault:TH001V_109DIA_000mt_8600-0"
		(layer "B.Cu")
		(at 168.841105 105.003605 180)
		(property "Reference" "P2"
			(at 0 2.11291 0)
			(unlocked yes)
			(layer "B.SilkS")
			(effects
				(font
					(face "Arial")
					(size 0.63 0.63)
					(thickness 0.254)
				)
				(justify mirror)
			)
		)
		(property "Value" "Mill-Max_8600-0-05-80-00-00-03-0"
			(at 22.534825 -2.89778 0)
			(unlocked yes)
			(layer "B.SilkS")
			(hide yes)
			(effects
				(font
					(face "Arial")
					(size 0.63 0.63)
					(thickness 0.254)
				)
				(justify mirror)
			)
		)
		(sheetname "SCH_SA45_DaughterCard")
		(sheetfile "SCH_SA45_DaughterCard.kicad_sch")
		(duplicate_pad_numbers_are_jumpers no)
		(fp_line
			(start 1.4 1.4)
			(end -1.4 1.4)
			(stroke
				(width 0.1)
				(type solid)
			)
			(layer "B.CrtYd")
		)
		(fp_line
			(start 1.4 -1.4)
			(end 1.4 1.4)
			(stroke
				(width 0.1)
				(type solid)
			)
			(layer "B.CrtYd")
		)
		(fp_line
			(start 1.4 -1.4)
			(end -1.4 -1.4)
			(stroke
				(width 0.1)
				(type solid)
			)
			(layer "B.CrtYd")
		)
		(fp_line
			(start -1.4 -1.4)
			(end -1.4 1.4)
			(stroke
				(width 0.1)
				(type solid)
			)
			(layer "B.CrtYd")
		)
		(fp_circle
			(center 0 0)
			(end 0 0.545)
			(stroke
				(width 0.1)
				(type solid)
			)
			(fill no)
			(layer "B.Fab")
		)
		(fp_text user "${REFERENCE}"
			(at 0.000005 0.159211 360)
			(unlocked yes)
			(layer "B.Fab")
			(effects
				(font
					(face "Arial")
					(size 0.8001 0.8001)
					(thickness 0.254)
				)
				(justify mirror)
			)
		)
		(pad "1" thru_hole circle
			(at 0 0 180)
			(size 2.09 2.09)
			(drill 1.09)
			(layers "*.Cu" "*.Mask")
			(remove_unused_layers no)
			(net "GND")
			(solder_mask_margin 0.05)
			(solder_paste_margin -2147.48364)
			(thermal_bridge_angle 90)
		)
	)
	(footprint "Vault:TH001V_109DIA_000mt_8600-0"
		(layer "B.Cu")
		(at 133.287105 81.993605 180)
		(property "Reference" "P7"
			(at 0.000005 1.67655 0)
			(unlocked yes)
			(layer "B.SilkS")
			(effects
				(font
					(face "Arial")
					(size 0.63 0.63)
					(thickness 0.254)
				)
				(justify mirror)
			)
		)
		(property "Value" "Mill-Max_8600-0-05-80-00-00-03-0"
			(at 22.534825 -2.89778 0)
			(unlocked yes)
			(layer "B.SilkS")
			(hide yes)
			(effects
				(font
					(face "Arial")
					(size 0.63 0.63)
					(thickness 0.254)
				)
				(justify mirror)
			)
		)
		(sheetname "SCH_SA45_DaughterCard")
		(sheetfile "SCH_SA45_DaughterCard.kicad_sch")
		(duplicate_pad_numbers_are_jumpers no)
		(fp_line
			(start 1.4 1.4)
			(end -1.4 1.4)
			(stroke
				(width 0.1)
				(type solid)
			)
			(layer "B.CrtYd")
		)
		(fp_line
			(start 1.4 -1.4)
			(end 1.4 1.4)
			(stroke
				(width 0.1)
				(type solid)
			)
			(layer "B.CrtYd")
		)
		(fp_line
			(start 1.4 -1.4)
			(end -1.4 -1.4)
			(stroke
				(width 0.1)
				(type solid)
			)
			(layer "B.CrtYd")
		)
		(fp_line
			(start -1.4 -1.4)
			(end -1.4 1.4)
			(stroke
				(width 0.1)
				(type solid)
			)
			(layer "B.CrtYd")
		)
		(fp_circle
			(center 0 0)
			(end 0 0.545)
			(stroke
				(width 0.1)
				(type solid)
			)
			(fill no)
			(layer "B.Fab")
		)
		(fp_text user "${REFERENCE}"
			(at 0 0.160971 360)
			(unlocked yes)
			(layer "B.Fab")
			(effects
				(font
					(face "Arial")
					(size 0.8001 0.8001)
					(thickness 0.254)
				)
				(justify mirror)
			)
		)
		(pad "1" thru_hole circle
			(at 0 -0.02 180)
			(size 2.09 2.09)
			(drill 1.09)
			(layers "*.Cu" "*.Mask")
			(remove_unused_layers no)
			(net "TX")
			(solder_mask_margin 0.05)
			(solder_paste_margin -2147.48364)
			(thermal_bridge_angle 90)
		)
	)
	(footprint "Vault:CAPC2013X145N"
		(layer "B.Cu")
		(at 144.976105 112.953605)
		(property "Reference" "C7"
			(at -2.69615 -0.12655 0)
			(unlocked yes)
			(layer "B.SilkS")
			(effects
				(font
					(face "Arial")
					(size 0.63 0.63)
					(thickness 0.254)
				)
				(justify mirror)
			)
		)
		(property "Value" "Murata_GRM21BR6YA106KE43L"
			(at -8.17338 -1.49206 0)
			(unlocked yes)
			(layer "B.SilkS")
			(hide yes)
			(effects
				(font
					(face "Arial")
					(size 0.63 0.63)
					(thickness 0.254)
				)
				(justify mirror)
			)
		)
		(sheetname "SCH_SA45_DaughterCard")
		(sheetfile "SCH_SA45_DaughterCard.kicad_sch")
		(duplicate_pad_numbers_are_jumpers no)
		(fp_line
			(start -1.8 -1.1)
			(end 1.8 -1.1)
			(stroke
				(width 0.1)
				(type solid)
			)
			(layer "B.CrtYd")
		)
		(fp_line
			(start -1.8 1.1)
			(end -1.8 -1.1)
			(stroke
				(width 0.1)
				(type solid)
			)
			(layer "B.CrtYd")
		)
		(fp_line
			(start -1.8 1.1)
			(end 1.8 1.1)
			(stroke
				(width 0.1)
				(type solid)
			)
			(layer "B.CrtYd")
		)
		(fp_line
			(start 1.8 1.1)
			(end 1.8 -1.1)
			(stroke
				(width 0.1)
				(type solid)
			)
			(layer "B.CrtYd")
		)
		(fp_line
			(start -1 -0.65001)
			(end 1 -0.65001)
			(stroke
				(width 0.05)
				(type solid)
			)
			(layer "B.Fab")
		)
		(fp_line
			(start -1 0.65)
			(end -1 -0.65001)
			(stroke
				(width 0.05)
				(type solid)
			)
			(layer "B.Fab")
		)
		(fp_line
			(start -1 0.65)
			(end 1 0.65)
			(stroke
				(width 0.05)
				(type solid)
			)
			(layer "B.Fab")
		)
		(fp_line
			(start 1 0.65)
			(end 1 -0.65001)
			(stroke
				(width 0.05)
				(type solid)
			)
			(layer "B.Fab")
		)
		(fp_text_box "${REFERENCE}"
			(start 1.14717 0.20756)
			(end -1.14713 -0.20757)
			(margins 0 0 0 0)
			(angle 180)
			(layer "B.Fab")
			(effects
				(font
					(face "Arial")
					(size 0.315 0.315)
					(thickness 0.254)
				)
				(justify top mirror)
			)
			(border no)
			(stroke
				(width 0.1)
				(type default)
			)
			(knockout no)
		)
		(pad "1" smd rect
			(at -0.9 0)
			(size 1.3 1.65)
			(layers "B.Cu" "B.Mask" "B.Paste")
			(net "+5V")
			(solder_mask_margin 0.05)
			(solder_paste_margin 0)
		)
		(pad "2" smd rect
			(at 0.9 0)
			(size 1.3 1.65)
			(layers "B.Cu" "B.Mask" "B.Paste")
			(net "GND")
			(solder_mask_margin 0.05)
			(solder_paste_margin 0)
		)
	)
)
